# S9S_MB_2U (Grand Teton) — schematic netlist excerpt (pin names and nets, part order shuffled) for the footprints in the layout excerpt that follows; sources: Cadence DE-HDL packaged netlist, KiCad conversion of 03242023_DA0F0TMBIJ0_F0T_Motherboard_J_brd_V01_OCP.brd

R4049  Q_RES  33.2 1% CHIP  pkg 0402LF  page 225 : A = RST_CPU1_DRAM_GH_PLD_LVT3_R_N ; B = RST_CPU1_DRAM_GH_PLD_LVT3_N
R667  Q_RES  0 5% EMPTY  pkg 0402LF  page 230 : A = I3C_SPD_DDREFGH_CPU1_R_SCL ; B = I3C_SPD_DDREFGH_CPU1_LVC1_R_SCL
C894  Q_CAP_DIFFBUS  DIFF BUS_0.22UF 6.3V 20% X6S  pkg C0201  page 174 : \1\ = P5E_CPU0_PE3_TX_C_DN<3> ; \2\ = P5E_CPU0_PE3_TX_DN<3>

(kicad_pcb
	(version 20260206)
	(generator "pcbnew")
	(generator_version "10.0")
	(general
		(thickness 1.6)
		(legacy_teardrops no)
	)
	(paper "A4")
	(title_block
		(title "03242023_DA0F0TMBIJ0_F0T_Motherboard_J_brd_V01_OCP.brd")
		(comment 1 "Grand Teton / footprints 373-375 of 6105")
	)
	(layers
		(0 "F.Cu" signal "TOP")
		(4 "In1.Cu" signal "GND")
		(6 "In2.Cu" signal "IN1")
		(8 "In3.Cu" signal "GND1")
		(10 "In4.Cu" signal "IN2")
		(12 "In5.Cu" signal "GND2")
		(14 "In6.Cu" signal "IN3")
		(16 "In7.Cu" signal "GND3")
		(18 "In8.Cu" signal "VCC")
		(20 "In9.Cu" signal "VCC1")
		(22 "In10.Cu" signal "GND4")
		(24 "In11.Cu" signal "IN4")
		(26 "In12.Cu" signal "GND5")
		(28 "In13.Cu" signal "IN5")
		(30 "In14.Cu" signal "GND6")
		(32 "In15.Cu" signal "IN6")
		(34 "In16.Cu" signal "GND7")
		(2 "B.Cu" signal "BOTTOM")
		(9 "F.Adhes" user "F.Adhesive")
		(11 "B.Adhes" user "B.Adhesive")
		(13 "F.Paste" user "Package Geometry/Pastemask Top")
		(15 "B.Paste" user "Package Geometry/Pastemask Bottom")
		(5 "F.SilkS" user "Ref Des/Silkscreen Top")
		(7 "B.SilkS" user "Ref Des/Silkscreen Bottom")
		(1 "F.Mask" user "Board Geometry/Soldermask Top")
		(3 "B.Mask" user "Board Geometry/Soldermask Bottom")
		(17 "Dwgs.User" user "User.Drawings")
		(19 "Cmts.User" user "User.Comments")
		(21 "Eco1.User" user "User.Eco1")
		(23 "Eco2.User" user "User.Eco2")
		(25 "Edge.Cuts" user "Board Geometry/Outline")
		(27 "Margin" user)
		(31 "F.CrtYd" user "Package Geometry/Place Bound Top")
		(29 "B.CrtYd" user "Package Geometry/Place Bound Bottom")
		(35 "F.Fab" user "Ref Des/Assembly Top")
		(33 "B.Fab" user "Ref Des/Assembly Bottom")
	)
	(footprint ""
		(layer "F.Cu")
		(at 409.50261 -408.517344 -90)
		(property "Reference" "C894"
			(at 0 0 270)
			(layer "F.SilkS")
			(hide yes)
			(effects
				(font
					(size 1.27 1.27)
				)
			)
		)
		(property "Value" ""
			(at 0 0 270)
			(layer "F.Fab")
			(effects
				(font
					(size 1.27 1.27)
				)
			)
		)
		(duplicate_pad_numbers_are_jumpers no)
		(fp_line
			(start -0.299974 0.150114)
			(end -0.299974 -0.150114)
			(stroke
				(width 0.1)
				(type default)
			)
			(layer "F.Fab")
		)
		(fp_line
			(start 0.299974 0.150114)
			(end -0.299974 0.150114)
			(stroke
				(width 0.1)
				(type default)
			)
			(layer "F.Fab")
		)
		(fp_line
			(start -0.299974 -0.150114)
			(end 0.299974 -0.150114)
			(stroke
				(width 0.1)
				(type default)
			)
			(layer "F.Fab")
		)
		(fp_line
			(start 0.299974 -0.150114)
			(end 0.299974 0.150114)
			(stroke
				(width 0.1)
				(type default)
			)
			(layer "F.Fab")
		)
		(pad "1" smd rect
			(at -0.2667 0 270)
			(size 0.3048 0.381)
			(layers "F.Cu" "F.Mask" "F.Paste")
			(net "P5E_CPU0_PE3_TX_C_DN<3>")
		)
		(pad "2" smd rect
			(at 0.2667 0 270)
			(size 0.3048 0.381)
			(layers "F.Cu" "F.Mask" "F.Paste")
			(net "P5E_CPU0_PE3_TX_DN<3>")
		)
	)
	(footprint ""
		(layer "F.Cu")
		(at 81.73847 -143.046704)
		(property "Reference" "R667"
			(at 0 0 0)
			(layer "F.SilkS")
			(hide yes)
			(effects
				(font
					(size 1.27 1.27)
				)
			)
		)
		(property "Value" ""
			(at 0 0 0)
			(layer "F.Fab")
			(effects
				(font
					(size 1.27 1.27)
				)
			)
		)
		(duplicate_pad_numbers_are_jumpers no)
		(fp_line
			(start -0.7874 -0.4064)
			(end 0.7874 -0.4064)
			(stroke
				(width 0.1524)
				(type default)
			)
			(layer "F.SilkS")
		)
		(fp_line
			(start -0.7874 0.4064)
			(end -0.7874 -0.4064)
			(stroke
				(width 0.1524)
				(type default)
			)
			(layer "F.SilkS")
		)
		(fp_line
			(start 0.7874 -0.4064)
			(end 0.7874 0.4064)
			(stroke
				(width 0.1524)
				(type default)
			)
			(layer "F.SilkS")
		)
		(fp_line
			(start 0.7874 0.4064)
			(end -0.7874 0.4064)
			(stroke
				(width 0.1524)
				(type default)
			)
			(layer "F.SilkS")
		)
		(fp_line
			(start -0.67945 -0.305054)
			(end -0.12065 -0.305054)
			(stroke
				(width 0.1)
				(type default)
			)
			(layer "F.Fab")
		)
		(fp_line
			(start -0.67945 0.3048)
			(end -0.67945 -0.305054)
			(stroke
				(width 0.1)
				(type default)
			)
			(layer "F.Fab")
		)
		(fp_line
			(start -0.12065 -0.305054)
			(end -0.12065 -0.2794)
			(stroke
				(width 0.1)
				(type default)
			)
			(layer "F.Fab")
		)
		(fp_line
			(start -0.12065 -0.2794)
			(end 0.12065 -0.2794)
			(stroke
				(width 0.1)
				(type default)
			)
			(layer "F.Fab")
		)
		(fp_line
			(start -0.12065 0.2794)
			(end -0.12065 0.3048)
			(stroke
				(width 0.1)
				(type default)
			)
			(layer "F.Fab")
		)
		(fp_line
			(start -0.12065 0.3048)
			(end -0.67945 0.3048)
			(stroke
				(width 0.1)
				(type default)
			)
			(layer "F.Fab")
		)
		(fp_line
			(start 0.120396 0.2794)
			(end -0.12065 0.2794)
			(stroke
				(width 0.1)
				(type default)
			)
			(layer "F.Fab")
		)
		(fp_line
			(start 0.120396 0.3048)
			(end 0.120396 0.2794)
			(stroke
				(width 0.1)
				(type default)
			)
			(layer "F.Fab")
		)
		(fp_line
			(start 0.12065 -0.3048)
			(end 0.67945 -0.3048)
			(stroke
				(width 0.1)
				(type default)
			)
			(layer "F.Fab")
		)
		(fp_line
			(start 0.12065 -0.2794)
			(end 0.12065 -0.3048)
			(stroke
				(width 0.1)
				(type default)
			)
			(layer "F.Fab")
		)
		(fp_line
			(start 0.67945 -0.3048)
			(end 0.67945 0.3048)
			(stroke
				(width 0.1)
				(type default)
			)
			(layer "F.Fab")
		)
		(fp_line
			(start 0.67945 0.3048)
			(end 0.120396 0.3048)
			(stroke
				(width 0.1)
				(type default)
			)
			(layer "F.Fab")
		)
		(pad "1" smd circle
			(at -0.40005 0)
			(size 0 0)
			(layers "F.Cu" "F.Mask" "F.Paste")
			(net "I3C_SPD_DDREFGH_CPU1_R_SCL")
		)
		(pad "2" smd circle
			(at 0.40005 0)
			(size 0 0)
			(layers "F.Cu" "F.Mask" "F.Paste")
			(net "I3C_SPD_DDREFGH_CPU1_LVC1_R_SCL")
		)
	)
	(footprint ""
		(layer "F.Cu")
		(at 125.48108 -106.238548 -90)
		(property "Reference" "R4049"
			(at 0 0 270)
			(layer "F.SilkS")
			(hide yes)
			(effects
				(font
					(size 1.27 1.27)
				)
			)
		)
		(property "Value" ""
			(at 0 0 270)
			(layer "F.Fab")
			(effects
				(font
					(size 1.27 1.27)
				)
			)
		)
		(duplicate_pad_numbers_are_jumpers no)
		(fp_line
			(start -0.7874 0.4064)
			(end -0.7874 -0.4064)
			(stroke
				(width 0.1524)
				(type default)
			)
			(layer "F.SilkS")
		)
		(fp_line
			(start 0.7874 0.4064)
			(end -0.7874 0.4064)
			(stroke
				(width 0.1524)
				(type default)
			)
			(layer "F.SilkS")
		)
		(fp_line
			(start -0.7874 -0.4064)
			(end 0.7874 -0.4064)
			(stroke
				(width 0.1524)
				(type default)
			)
			(layer "F.SilkS")
		)
		(fp_line
			(start 0.7874 -0.4064)
			(end 0.7874 0.4064)
			(stroke
				(width 0.1524)
				(type default)
			)
			(layer "F.SilkS")
		)
		(fp_line
			(start -0.67945 0.3048)
			(end -0.67945 -0.305054)
			(stroke
				(width 0.1)
				(type default)
			)
			(layer "F.Fab")
		)
		(fp_line
			(start -0.12065 0.3048)
			(end -0.67945 0.3048)
			(stroke
				(width 0.1)
				(type default)
			)
			(layer "F.Fab")
		)
		(fp_line
			(start 0.120396 0.3048)
			(end 0.120396 0.2794)
			(stroke
				(width 0.1)
				(type default)
			)
			(layer "F.Fab")
		)
		(fp_line
			(start 0.67945 0.3048)
			(end 0.120396 0.3048)
			(stroke
				(width 0.1)
				(type default)
			)
			(layer "F.Fab")
		)
		(fp_line
			(start -0.12065 0.2794)
			(end -0.12065 0.3048)
			(stroke
				(width 0.1)
				(type default)
			)
			(layer "F.Fab")
		)
		(fp_line
			(start 0.120396 0.2794)
			(end -0.12065 0.2794)
			(stroke
				(width 0.1)
				(type default)
			)
			(layer "F.Fab")
		)
		(fp_line
			(start -0.12065 -0.2794)
			(end 0.12065 -0.2794)
			(stroke
				(width 0.1)
				(type default)
			)
			(layer "F.Fab")
		)
		(fp_line
			(start 0.12065 -0.2794)
			(end 0.12065 -0.3048)
			(stroke
				(width 0.1)
				(type default)
			)
			(layer "F.Fab")
		)
		(fp_line
			(start 0.12065 -0.3048)
			(end 0.67945 -0.3048)
			(stroke
				(width 0.1)
				(type default)
			)
			(layer "F.Fab")
		)
		(fp_line
			(start 0.67945 -0.3048)
			(end 0.67945 0.3048)
			(stroke
				(width 0.1)
				(type default)
			)
			(layer "F.Fab")
		)
		(fp_line
			(start -0.67945 -0.305054)
			(end -0.12065 -0.305054)
			(stroke
				(width 0.1)
				(type default)
			)
			(layer "F.Fab")
		)
		(fp_line
			(start -0.12065 -0.305054)
			(end -0.12065 -0.2794)
			(stroke
				(width 0.1)
				(type default)
			)
			(layer "F.Fab")
		)
		(pad "1" smd circle
			(at -0.40005 0 270)
			(size 0 0)
			(layers "F.Cu" "F.Mask" "F.Paste")
			(net "RST_CPU1_DRAM_GH_PLD_LVT3_R_N")
		)
		(pad "2" smd circle
			(at 0.40005 0 270)
			(size 0 0)
			(layers "F.Cu" "F.Mask" "F.Paste")
			(net "RST_CPU1_DRAM_GH_PLD_LVT3_N")
		)
	)
)
